(kicad_pcb
	(version 20260206)
	(generator "pcbnew")
	(generator_version "10.0")
	(general
		(thickness 1.6)
		(legacy_teardrops no)
	)
	(paper "A4")
	(title_block
		(title "peb — Lightning_PEB_BRD.brd")
		(comment 1 "Lightning (Wiwynn / Facebook NVMe JBOF) / footprints 578-585 of 2563")
	)
	(layers
		(0 "F.Cu" signal "TOP")
		(4 "In1.Cu" signal "L2GND")
		(6 "In2.Cu" signal "L3")
		(8 "In3.Cu" signal "L4VCC")
		(10 "In4.Cu" signal "L5VCC")
		(12 "In5.Cu" signal "L6")
		(14 "In6.Cu" signal "L7GND")
		(2 "B.Cu" signal "BOTTOM")
		(9 "F.Adhes" user "F.Adhesive")
		(11 "B.Adhes" user "B.Adhesive")
		(13 "F.Paste" user "Package Geometry/Pastemask Top")
		(15 "B.Paste" user "Package Geometry/Pastemask Bottom")
		(5 "F.SilkS" user "Ref Des/Silkscreen Top")
		(7 "B.SilkS" user "Ref Des/Silkscreen Bottom")
		(1 "F.Mask" user "Board Geometry/Soldermask Top")
		(3 "B.Mask" user "Board Geometry/Soldermask Bottom")
		(17 "Dwgs.User" user "User.Drawings")
		(19 "Cmts.User" user "User.Comments")
		(21 "Eco1.User" user "User.Eco1")
		(23 "Eco2.User" user "User.Eco2")
		(25 "Edge.Cuts" user "Board Geometry/Outline")
		(27 "Margin" user)
		(31 "F.CrtYd" user "Package Geometry/Place Bound Top")
		(29 "B.CrtYd" user "Package Geometry/Place Bound Bottom")
		(35 "F.Fab" user "Ref Des/Assembly Top")
		(33 "B.Fab" user "Ref Des/Assembly Bottom")
	)
	(footprint ""
		(layer "F.Cu")
		(at 215.629236 0.46101 -90)
		(property "Reference" "SLED29"
			(at 0 0 270)
			(layer "F.SilkS")
			(hide yes)
			(effects
				(font
					(size 1.27 1.27)
				)
			)
		)
		(property "Value" "LED-YG-51-GP"
			(at -2.6924 -1.4224 270)
			(unlocked yes)
			(layer "F.Fab")
			(hide yes)
			(effects
				(font
					(size 1.016 1.016)
					(thickness 0.1524)
				)
			)
		)
		(property "Device Type" "LED1608AKH40"
			(at -2.6924 -2.9464 270)
			(unlocked yes)
			(layer "F.Fab")
			(hide yes)
			(effects
				(font
					(size 1.016 1.016)
					(thickness 0.1524)
				)
			)
		)
		(duplicate_pad_numbers_are_jumpers no)
		(fp_line
			(start -0.7493 1.651)
			(end -0.7493 1.1811)
			(stroke
				(width 0.3302)
				(type default)
			)
			(layer "F.SilkS")
		)
		(fp_line
			(start 0.7493 1.651)
			(end 0.7493 1.1811)
			(stroke
				(width 0.3302)
				(type default)
			)
			(layer "F.SilkS")
		)
		(fp_line
			(start -0.5969 1.5494)
			(end 0.5842 1.5494)
			(stroke
				(width 0.508)
				(type default)
			)
			(layer "F.SilkS")
		)
		(fp_line
			(start -0.6604 1.3716)
			(end -0.6604 -1.3716)
			(stroke
				(width 0.1524)
				(type default)
			)
			(layer "F.SilkS")
		)
		(fp_line
			(start 0.6604 1.3716)
			(end -0.6604 1.3716)
			(stroke
				(width 0.1524)
				(type default)
			)
			(layer "F.SilkS")
		)
		(fp_line
			(start -0.6604 -1.3716)
			(end 0.6604 -1.3716)
			(stroke
				(width 0.1524)
				(type default)
			)
			(layer "F.SilkS")
		)
		(fp_line
			(start 0.6604 -1.3716)
			(end 0.6604 1.3716)
			(stroke
				(width 0.1524)
				(type default)
			)
			(layer "F.SilkS")
		)
		(fp_rect
			(start -0.6223 1.3335)
			(end 0.6223 -1.3335)
			(stroke
				(width 0)
				(type default)
			)
			(fill no)
			(layer "F.CrtYd")
		)
		(fp_rect
			(start -0.6223 1.3335)
			(end 0.6223 -1.3335)
			(stroke
				(width 0)
				(type default)
			)
			(fill no)
			(layer "F.Fab")
		)
		(pad "A" smd custom
			(at 0 -0.762 270)
			(size 0.2159 0.2159)
			(layers "F.Cu" "F.Mask" "F.Paste")
			(net "SLED29_A")
			(options
				(clearance outline)
				(anchor circle)
			)
			(primitives
				(gr_poly
					(pts
						(arc
							(start -0.3302 -0.4318)
							(mid -0.402042 -0.402042)
							(end -0.4318 -0.3302)
						)
						(arc
							(start -0.4318 0.3302)
							(mid -0.402042 0.402042)
							(end -0.3302 0.4318)
						)
						(arc
							(start 0.3302 0.4318)
							(mid 0.402042 0.402042)
							(end 0.4318 0.3302)
						)
						(arc
							(start 0.4318 -0.3302)
							(mid 0.402042 -0.402042)
							(end 0.3302 -0.4318)
						)
					)
					(width 0)
					(fill yes)
				)
			)
		)
		(pad "K" smd custom
			(at 0 0.762 270)
			(size 0.2159 0.2159)
			(layers "F.Cu" "F.Mask" "F.Paste")
			(net "Q22_D")
			(options
				(clearance outline)
				(anchor circle)
			)
			(primitives
				(gr_poly
					(pts
						(arc
							(start -0.3302 -0.4318)
							(mid -0.402042 -0.402042)
							(end -0.4318 -0.3302)
						)
						(arc
							(start -0.4318 0.3302)
							(mid -0.402042 0.402042)
							(end -0.3302 0.4318)
						)
						(arc
							(start 0.3302 0.4318)
							(mid 0.402042 0.402042)
							(end 0.4318 0.3302)
						)
						(arc
							(start 0.4318 -0.3302)
							(mid 0.402042 -0.402042)
							(end 0.3302 -0.4318)
						)
					)
					(width 0)
					(fill yes)
				)
			)
		)
	)
	(footprint ""
		(layer "F.Cu")
		(at 20.701 -161.544)
		(property "Reference" "C275"
			(at 0 0 0)
			(layer "F.SilkS")
			(hide yes)
			(effects
				(font
					(size 1.27 1.27)
				)
			)
		)
		(property "Value" "SCD1U16V2KX-3GP"
			(at 1.1811 -2.7051 0)
			(unlocked yes)
			(layer "F.Fab")
			(hide yes)
			(effects
				(font
					(size 1.016 1.016)
					(thickness 0.1524)
				)
			)
		)
		(property "Device Type" "C402H22"
			(at 1.1811 -4.2291 0)
			(unlocked yes)
			(layer "F.Fab")
			(hide yes)
			(effects
				(font
					(size 1.016 1.016)
					(thickness 0.1524)
				)
			)
		)
		(duplicate_pad_numbers_are_jumpers no)
		(fp_rect
			(start -0.4318 0.9525)
			(end 0.4318 -0.9525)
			(stroke
				(width 0)
				(type default)
			)
			(fill no)
			(layer "F.CrtYd")
		)
		(fp_rect
			(start -0.4318 0.9525)
			(end 0.4318 -0.9525)
			(stroke
				(width 0)
				(type default)
			)
			(fill no)
			(layer "F.Fab")
		)
		(pad "1" smd custom
			(at 0 -0.4445)
			(size 0.1524 0.1524)
			(layers "F.Cu" "F.Mask" "F.Paste")
			(net "P3V3_STBY")
			(options
				(clearance outline)
				(anchor circle)
			)
			(primitives
				(gr_poly
					(pts
						(arc
							(start 0.3048 -0.2032)
							(mid 0.275042 -0.275042)
							(end 0.2032 -0.3048)
						)
						(arc
							(start -0.2032 -0.3048)
							(mid -0.275042 -0.275042)
							(end -0.3048 -0.2032)
						)
						(arc
							(start -0.3048 0.2032)
							(mid -0.275042 0.275042)
							(end -0.2032 0.3048)
						)
						(arc
							(start 0.2032 0.3048)
							(mid 0.275042 0.275042)
							(end 0.3048 0.2032)
						)
					)
					(width 0)
					(fill yes)
				)
			)
		)
		(pad "2" smd custom
			(at 0 0.4445)
			(size 0.1524 0.1524)
			(layers "F.Cu" "F.Mask" "F.Paste")
			(net "GND")
			(options
				(clearance outline)
				(anchor circle)
			)
			(primitives
				(gr_poly
					(pts
						(arc
							(start 0.3048 -0.2032)
							(mid 0.275042 -0.275042)
							(end 0.2032 -0.3048)
						)
						(arc
							(start -0.2032 -0.3048)
							(mid -0.275042 -0.275042)
							(end -0.3048 -0.2032)
						)
						(arc
							(start -0.3048 0.2032)
							(mid -0.275042 0.275042)
							(end -0.2032 0.3048)
						)
						(arc
							(start 0.2032 0.3048)
							(mid 0.275042 0.275042)
							(end 0.3048 0.2032)
						)
					)
					(width 0)
					(fill yes)
				)
			)
		)
	)
	(footprint ""
		(layer "F.Cu")
		(at 339.808058 -212.420454 180)
		(property "Reference" "C57"
			(at 0 0 180)
			(layer "F.SilkS")
			(hide yes)
			(effects
				(font
					(size 1.27 1.27)
				)
			)
		)
		(property "Value" "SCD22U10V2KX-1GP"
			(at 1.1811 -2.7051 180)
			(unlocked yes)
			(layer "F.Fab")
			(hide yes)
			(effects
				(font
					(size 1.016 1.016)
					(thickness 0.1524)
				)
			)
		)
		(property "Device Type" "C402H22"
			(at 1.1811 -4.2291 180)
			(unlocked yes)
			(layer "F.Fab")
			(hide yes)
			(effects
				(font
					(size 1.016 1.016)
					(thickness 0.1524)
				)
			)
		)
		(duplicate_pad_numbers_are_jumpers no)
		(fp_rect
			(start -0.4318 0.9525)
			(end 0.4318 -0.9525)
			(stroke
				(width 0)
				(type default)
			)
			(fill no)
			(layer "F.CrtYd")
		)
		(fp_rect
			(start -0.4318 0.9525)
			(end 0.4318 -0.9525)
			(stroke
				(width 0)
				(type default)
			)
			(fill no)
			(layer "F.Fab")
		)
		(pad "1" smd custom
			(at 0 -0.4445 180)
			(size 0.1524 0.1524)
			(layers "F.Cu" "F.Mask" "F.Paste")
			(net "PCIE_TX_CAP_N17")
			(options
				(clearance outline)
				(anchor circle)
			)
			(primitives
				(gr_poly
					(pts
						(arc
							(start 0.3048 -0.2032)
							(mid 0.275042 -0.275042)
							(end 0.2032 -0.3048)
						)
						(arc
							(start -0.2032 -0.3048)
							(mid -0.275042 -0.275042)
							(end -0.3048 -0.2032)
						)
						(arc
							(start -0.3048 0.2032)
							(mid -0.275042 0.275042)
							(end -0.2032 0.3048)
						)
						(arc
							(start 0.2032 0.3048)
							(mid 0.275042 0.275042)
							(end 0.3048 0.2032)
						)
					)
					(width 0)
					(fill yes)
				)
			)
		)
		(pad "2" smd custom
			(at 0 0.4445 180)
			(size 0.1524 0.1524)
			(layers "F.Cu" "F.Mask" "F.Paste")
			(net "PCIE_TX_N17")
			(options
				(clearance outline)
				(anchor circle)
			)
			(primitives
				(gr_poly
					(pts
						(arc
							(start 0.3048 -0.2032)
							(mid 0.275042 -0.275042)
							(end 0.2032 -0.3048)
						)
						(arc
							(start -0.2032 -0.3048)
							(mid -0.275042 -0.275042)
							(end -0.3048 -0.2032)
						)
						(arc
							(start -0.3048 0.2032)
							(mid -0.275042 0.275042)
							(end -0.2032 0.3048)
						)
						(arc
							(start 0.2032 0.3048)
							(mid 0.275042 0.275042)
							(end 0.3048 0.2032)
						)
					)
					(width 0)
					(fill yes)
				)
			)
		)
	)
	(footprint ""
		(layer "F.Cu")
		(at 17.1704 -83.5914 180)
		(property "Reference" "C628"
			(at 0 0 180)
			(layer "F.SilkS")
			(hide yes)
			(effects
				(font
					(size 1.27 1.27)
				)
			)
		)
		(property "Value" "SCD1U16V2KX-3GP"
			(at 1.1811 -2.7051 180)
			(unlocked yes)
			(layer "F.Fab")
			(hide yes)
			(effects
				(font
					(size 1.016 1.016)
					(thickness 0.1524)
				)
			)
		)
		(property "Device Type" "C402H22"
			(at 1.1811 -4.2291 180)
			(unlocked yes)
			(layer "F.Fab")
			(hide yes)
			(effects
				(font
					(size 1.016 1.016)
					(thickness 0.1524)
				)
			)
		)
		(duplicate_pad_numbers_are_jumpers no)
		(fp_rect
			(start -0.4318 0.9525)
			(end 0.4318 -0.9525)
			(stroke
				(width 0)
				(type default)
			)
			(fill no)
			(layer "F.CrtYd")
		)
		(fp_rect
			(start -0.4318 0.9525)
			(end 0.4318 -0.9525)
			(stroke
				(width 0)
				(type default)
			)
			(fill no)
			(layer "F.Fab")
		)
		(pad "1" smd custom
			(at 0 -0.4445 180)
			(size 0.1524 0.1524)
			(layers "F.Cu" "F.Mask" "F.Paste")
			(net "P3V3_STBY")
			(options
				(clearance outline)
				(anchor circle)
			)
			(primitives
				(gr_poly
					(pts
						(arc
							(start 0.3048 -0.2032)
							(mid 0.275042 -0.275042)
							(end 0.2032 -0.3048)
						)
						(arc
							(start -0.2032 -0.3048)
							(mid -0.275042 -0.275042)
							(end -0.3048 -0.2032)
						)
						(arc
							(start -0.3048 0.2032)
							(mid -0.275042 0.275042)
							(end -0.2032 0.3048)
						)
						(arc
							(start 0.2032 0.3048)
							(mid 0.275042 0.275042)
							(end 0.3048 0.2032)
						)
					)
					(width 0)
					(fill yes)
				)
			)
		)
		(pad "2" smd custom
			(at 0 0.4445 180)
			(size 0.1524 0.1524)
			(layers "F.Cu" "F.Mask" "F.Paste")
			(net "GND")
			(options
				(clearance outline)
				(anchor circle)
			)
			(primitives
				(gr_poly
					(pts
						(arc
							(start 0.3048 -0.2032)
							(mid 0.275042 -0.275042)
							(end 0.2032 -0.3048)
						)
						(arc
							(start -0.2032 -0.3048)
							(mid -0.275042 -0.275042)
							(end -0.3048 -0.2032)
						)
						(arc
							(start -0.3048 0.2032)
							(mid -0.275042 0.275042)
							(end -0.2032 0.3048)
						)
						(arc
							(start 0.2032 0.3048)
							(mid 0.275042 0.275042)
							(end 0.3048 0.2032)
						)
					)
					(width 0)
					(fill yes)
				)
			)
		)
	)
	(footprint ""
		(layer "F.Cu")
		(at 31.877 -118.364)
		(property "Reference" "TP243"
			(at 0 0 0)
			(layer "F.SilkS")
			(hide yes)
			(effects
				(font
					(size 1.27 1.27)
				)
			)
		)
		(property "Value" "TPAD28-2-GP"
			(at -0.0127 -1.6637 0)
			(unlocked yes)
			(layer "F.Fab")
			(hide yes)
			(effects
				(font
					(size 1.016 1.016)
					(thickness 0.1524)
				)
			)
		)
		(property "Device Type" "TPAD28"
			(at -0.0127 -3.1877 0)
			(unlocked yes)
			(layer "F.Fab")
			(hide yes)
			(effects
				(font
					(size 1.016 1.016)
					(thickness 0.1524)
				)
			)
		)
		(duplicate_pad_numbers_are_jumpers no)
		(fp_poly
			(pts
				(arc
					(start 0.3556 0)
					(mid -0.3556 0)
					(end 0.3556 0)
				)
			)
			(stroke
				(width 0)
				(type default)
			)
			(fill no)
			(layer "F.CrtYd")
		)
		(fp_poly
			(pts
				(arc
					(start 0.6096 0)
					(mid -0.6096 0)
					(end 0.6096 0)
				)
			)
			(stroke
				(width 0)
				(type default)
			)
			(fill no)
			(layer "F.Fab")
		)
		(pad "1" smd circle
			(at 0 0)
			(size 0.7112 0.7112)
			(layers "F.Cu" "F.Mask" "F.Paste")
			(net "TP_GPIOD3")
		)
	)
	(footprint ""
		(layer "F.Cu")
		(at 136.30275 -41.519602 90)
		(property "Reference" "R730"
			(at 0 0 90)
			(layer "F.SilkS")
			(hide yes)
			(effects
				(font
					(size 1.27 1.27)
				)
			)
		)
		(property "Value" "15KR2F-GP"
			(at 0.064008 -3.993896 90)
			(unlocked yes)
			(layer "F.Fab")
			(hide yes)
			(effects
				(font
					(size 1.016 1.016)
					(thickness 0.1524)
				)
			)
		)
		(property "Device Type" "R402H16"
			(at 0.064008 -5.517896 90)
			(unlocked yes)
			(layer "F.Fab")
			(hide yes)
			(effects
				(font
					(size 1.016 1.016)
					(thickness 0.1524)
				)
			)
		)
		(duplicate_pad_numbers_are_jumpers no)
		(fp_line
			(start 0.508 -0.9398)
			(end -0.508 -0.9398)
			(stroke
				(width 0.1524)
				(type default)
			)
			(layer "F.SilkS")
		)
		(fp_line
			(start -0.508 -0.9398)
			(end -0.508 0.9398)
			(stroke
				(width 0.1524)
				(type default)
			)
			(layer "F.SilkS")
		)
		(fp_rect
			(start -0.508 0.9398)
			(end 0.508 -0.9398)
			(stroke
				(width 0)
				(type default)
			)
			(fill no)
			(layer "F.CrtYd")
		)
		(fp_rect
			(start -0.508 0.9398)
			(end 0.508 -0.9398)
			(stroke
				(width 0)
				(type default)
			)
			(fill no)
			(layer "F.Fab")
		)
		(pad "1" smd custom
			(at 0 -0.4445 90)
			(size 0.1397 0.1397)
			(layers "F.Cu" "F.Mask" "F.Paste")
			(net "DUT_VDDO")
			(options
				(clearance outline)
				(anchor circle)
			)
			(primitives
				(gr_poly
					(pts
						(arc
							(start -0.1778 -0.2794)
							(mid -0.249642 -0.249642)
							(end -0.2794 -0.1778)
						)
						(arc
							(start -0.2794 0.1778)
							(mid -0.249642 0.249642)
							(end -0.1778 0.2794)
						)
						(arc
							(start 0.1778 0.2794)
							(mid 0.249642 0.249642)
							(end 0.2794 0.1778)
						)
						(arc
							(start 0.2794 -0.1778)
							(mid 0.249642 -0.249642)
							(end 0.1778 -0.2794)
						)
					)
					(width 0)
					(fill yes)
				)
			)
		)
		(pad "2" smd custom
			(at 0 0.4445 90)
			(size 0.1397 0.1397)
			(layers "F.Cu" "F.Mask" "F.Paste")
			(net "DUT_TDO")
			(options
				(clearance outline)
				(anchor circle)
			)
			(primitives
				(gr_poly
					(pts
						(arc
							(start -0.1778 -0.2794)
							(mid -0.249642 -0.249642)
							(end -0.2794 -0.1778)
						)
						(arc
							(start -0.2794 0.1778)
							(mid -0.249642 0.249642)
							(end -0.1778 0.2794)
						)
						(arc
							(start 0.1778 0.2794)
							(mid 0.249642 0.249642)
							(end 0.2794 0.1778)
						)
						(arc
							(start 0.2794 -0.1778)
							(mid 0.249642 -0.249642)
							(end 0.1778 -0.2794)
						)
					)
					(width 0)
					(fill yes)
				)
			)
		)
	)
	(footprint ""
		(layer "F.Cu")
		(at 38.5064 -103.632)
		(property "Reference" "R656"
			(at 0 0 0)
			(layer "F.SilkS")
			(hide yes)
			(effects
				(font
					(size 1.27 1.27)
				)
			)
		)
		(property "Value" "4K7R2F-GP"
			(at 0.064008 -3.993896 0)
			(unlocked yes)
			(layer "F.Fab")
			(hide yes)
			(effects
				(font
					(size 1.016 1.016)
					(thickness 0.1524)
				)
			)
		)
		(property "Device Type" "R402H16"
			(at 0.064008 -5.517896 0)
			(unlocked yes)
			(layer "F.Fab")
			(hide yes)
			(effects
				(font
					(size 1.016 1.016)
					(thickness 0.1524)
				)
			)
		)
		(duplicate_pad_numbers_are_jumpers no)
		(fp_line
			(start -0.508 -0.9398)
			(end -0.508 0.9398)
			(stroke
				(width 0.1524)
				(type default)
			)
			(layer "F.SilkS")
		)
		(fp_line
			(start 0.508 -0.9398)
			(end -0.508 -0.9398)
			(stroke
				(width 0.1524)
				(type default)
			)
			(layer "F.SilkS")
		)
		(fp_rect
			(start -0.508 0.9398)
			(end 0.508 -0.9398)
			(stroke
				(width 0)
				(type default)
			)
			(fill no)
			(layer "F.CrtYd")
		)
		(fp_rect
			(start -0.508 0.9398)
			(end 0.508 -0.9398)
			(stroke
				(width 0)
				(type default)
			)
			(fill no)
			(layer "F.Fab")
		)
		(pad "1" smd custom
			(at 0 -0.4445)
			(size 0.1397 0.1397)
			(layers "F.Cu" "F.Mask" "F.Paste")
			(net "SPI_FLASH_SELECT")
			(options
				(clearance outline)
				(anchor circle)
			)
			(primitives
				(gr_poly
					(pts
						(arc
							(start -0.1778 -0.2794)
							(mid -0.249642 -0.249642)
							(end -0.2794 -0.1778)
						)
						(arc
							(start -0.2794 0.1778)
							(mid -0.249642 0.249642)
							(end -0.1778 0.2794)
						)
						(arc
							(start 0.1778 0.2794)
							(mid 0.249642 0.249642)
							(end 0.2794 0.1778)
						)
						(arc
							(start 0.2794 -0.1778)
							(mid 0.249642 -0.249642)
							(end 0.1778 -0.2794)
						)
					)
					(width 0)
					(fill yes)
				)
			)
		)
		(pad "2" smd custom
			(at 0 0.4445)
			(size 0.1397 0.1397)
			(layers "F.Cu" "F.Mask" "F.Paste")
			(net "P3V3_STBY")
			(options
				(clearance outline)
				(anchor circle)
			)
			(primitives
				(gr_poly
					(pts
						(arc
							(start -0.1778 -0.2794)
							(mid -0.249642 -0.249642)
							(end -0.2794 -0.1778)
						)
						(arc
							(start -0.2794 0.1778)
							(mid -0.249642 0.249642)
							(end -0.1778 0.2794)
						)
						(arc
							(start 0.1778 0.2794)
							(mid 0.249642 0.249642)
							(end 0.2794 0.1778)
						)
						(arc
							(start 0.2794 -0.1778)
							(mid 0.249642 -0.249642)
							(end 0.1778 -0.2794)
						)
					)
					(width 0)
					(fill yes)
				)
			)
		)
	)
	(footprint ""
		(layer "F.Cu")
		(at 264.541 -26.289 180)
		(property "Reference" "R777"
			(at 0 0 180)
			(layer "F.SilkS")
			(hide yes)
			(effects
				(font
					(size 1.27 1.27)
				)
			)
		)
		(property "Value" "2KR2F-3-GP"
			(at 0.064008 -3.993896 180)
			(unlocked yes)
			(layer "F.Fab")
			(hide yes)
			(effects
				(font
					(size 1.016 1.016)
					(thickness 0.1524)
				)
			)
		)
		(property "Device Type" "R402H16"
			(at 0.064008 -5.517896 180)
			(unlocked yes)
			(layer "F.Fab")
			(hide yes)
			(effects
				(font
					(size 1.016 1.016)
					(thickness 0.1524)
				)
			)
		)
		(duplicate_pad_numbers_are_jumpers no)
		(fp_line
			(start 0.508 -0.9398)
			(end -0.508 -0.9398)
			(stroke
				(width 0.1524)
				(type default)
			)
			(layer "F.SilkS")
		)
		(fp_line
			(start -0.508 -0.9398)
			(end -0.508 0.9398)
			(stroke
				(width 0.1524)
				(type default)
			)
			(layer "F.SilkS")
		)
		(fp_rect
			(start -0.508 0.9398)
			(end 0.508 -0.9398)
			(stroke
				(width 0)
				(type default)
			)
			(fill no)
			(layer "F.CrtYd")
		)
		(fp_rect
			(start -0.508 0.9398)
			(end 0.508 -0.9398)
			(stroke
				(width 0)
				(type default)
			)
			(fill no)
			(layer "F.Fab")
		)
		(pad "1" smd custom
			(at 0 -0.4445 180)
			(size 0.1397 0.1397)
			(layers "F.Cu" "F.Mask" "F.Paste")
			(net "P3V3_GPIO")
			(options
				(clearance outline)
				(anchor circle)
			)
			(primitives
				(gr_poly
					(pts
						(arc
							(start -0.1778 -0.2794)
							(mid -0.249642 -0.249642)
							(end -0.2794 -0.1778)
						)
						(arc
							(start -0.2794 0.1778)
							(mid -0.249642 0.249642)
							(end -0.1778 0.2794)
						)
						(arc
							(start 0.1778 0.2794)
							(mid 0.249642 0.249642)
							(end 0.2794 0.1778)
						)
						(arc
							(start 0.2794 -0.1778)
							(mid 0.249642 -0.249642)
							(end 0.1778 -0.2794)
						)
					)
					(width 0)
					(fill yes)
				)
			)
		)
		(pad "2" smd custom
			(at 0 0.4445 180)
			(size 0.1397 0.1397)
			(layers "F.Cu" "F.Mask" "F.Paste")
			(net "TWI_SDA3")
			(options
				(clearance outline)
				(anchor circle)
			)
			(primitives
				(gr_poly
					(pts
						(arc
							(start -0.1778 -0.2794)
							(mid -0.249642 -0.249642)
							(end -0.2794 -0.1778)
						)
						(arc
							(start -0.2794 0.1778)
							(mid -0.249642 0.249642)
							(end -0.1778 0.2794)
						)
						(arc
							(start 0.1778 0.2794)
							(mid 0.249642 0.249642)
							(end 0.2794 0.1778)
						)
						(arc
							(start 0.2794 -0.1778)
							(mid 0.249642 -0.249642)
							(end 0.1778 -0.2794)
						)
					)
					(width 0)
					(fill yes)
				)
			)
		)
	)
)
